(kicad_pcb
	(version 20260206)
	(generator "pcbnew")
	(generator_version "10.0")
	(general
		(thickness 1.6)
		(legacy_teardrops no)
	)
	(paper "A4")
	(title_block
		(title "Bryce Canyon_SCC_16316-1_OCP.brd")
		(comment 1 "Bryce Canyon / footprints 911-918 of 1561")
	)
	(layers
		(0 "F.Cu" signal "TOP")
		(4 "In1.Cu" signal "L2GND")
		(6 "In2.Cu" signal "L3")
		(8 "In3.Cu" signal "L4VCC")
		(10 "In4.Cu" signal "L5VCC")
		(12 "In5.Cu" signal "L6")
		(14 "In6.Cu" signal "L7GND")
		(2 "B.Cu" signal "BOTTOM")
		(9 "F.Adhes" user "F.Adhesive")
		(11 "B.Adhes" user "B.Adhesive")
		(13 "F.Paste" user "Package Geometry/Pastemask Top")
		(15 "B.Paste" user "Package Geometry/Pastemask Bottom")
		(5 "F.SilkS" user "Ref Des/Silkscreen Top")
		(7 "B.SilkS" user "Ref Des/Silkscreen Bottom")
		(1 "F.Mask" user "Board Geometry/Soldermask Top")
		(3 "B.Mask" user "Board Geometry/Soldermask Bottom")
		(17 "Dwgs.User" user "User.Drawings")
		(19 "Cmts.User" user "User.Comments")
		(21 "Eco1.User" user "User.Eco1")
		(23 "Eco2.User" user "User.Eco2")
		(25 "Edge.Cuts" user "Board Geometry/Outline")
		(27 "Margin" user)
		(31 "F.CrtYd" user "Package Geometry/Place Bound Top")
		(29 "B.CrtYd" user "Package Geometry/Place Bound Bottom")
		(35 "F.Fab" user "Ref Des/Assembly Top")
		(33 "B.Fab" user "Ref Des/Assembly Bottom")
	)
	(footprint ""
		(layer "B.Cu")
		(at 109.4867 -59.4487)
		(property "Reference" "C537"
			(at 0 0 0)
			(layer "B.SilkS")
			(hide yes)
			(effects
				(font
					(size 1.27 1.27)
				)
				(justify mirror)
			)
		)
		(property "Value" "SCD1U6D3V1KX-GP"
			(at 2.8321 -1.7399 0)
			(unlocked yes)
			(layer "B.Fab")
			(hide yes)
			(effects
				(font
					(size 1.016 1.016)
					(thickness 0.1524)
				)
				(justify mirror)
			)
		)
		(property "Device Type" "C0201H13"
			(at 2.8321 -3.2639 0)
			(unlocked yes)
			(layer "B.Fab")
			(hide yes)
			(effects
				(font
					(size 1.016 1.016)
					(thickness 0.1524)
				)
				(justify mirror)
			)
		)
		(duplicate_pad_numbers_are_jumpers no)
		(fp_rect
			(start 0.2794 0.6477)
			(end -0.2794 -0.6477)
			(stroke
				(width 0)
				(type default)
			)
			(fill no)
			(layer "B.CrtYd")
		)
		(fp_rect
			(start 0.2794 0.6477)
			(end -0.2794 -0.6477)
			(stroke
				(width 0)
				(type default)
			)
			(fill no)
			(layer "B.Fab")
		)
		(pad "1" smd custom
			(at 0 -0.2794 180)
			(size 0.0762 0.0762)
			(layers "B.Cu" "B.Mask" "B.Paste")
			(net "GB_VDDA")
			(options
				(clearance outline)
				(anchor circle)
			)
			(primitives
				(gr_poly
					(pts
						(arc
							(start 0.1524 0.127)
							(mid 0.137521 0.162921)
							(end 0.1016 0.1778)
						)
						(arc
							(start -0.1016 0.1778)
							(mid -0.137521 0.162921)
							(end -0.1524 0.127)
						)
						(arc
							(start -0.1524 -0.127)
							(mid -0.137521 -0.162921)
							(end -0.1016 -0.1778)
						)
						(arc
							(start 0.1016 -0.1778)
							(mid 0.137521 -0.162921)
							(end 0.1524 -0.127)
						)
					)
					(width 0)
					(fill yes)
				)
			)
		)
		(pad "2" smd custom
			(at 0 0.2794 180)
			(size 0.0762 0.0762)
			(layers "B.Cu" "B.Mask" "B.Paste")
			(net "GND")
			(options
				(clearance outline)
				(anchor circle)
			)
			(primitives
				(gr_poly
					(pts
						(arc
							(start 0.1524 0.127)
							(mid 0.137521 0.162921)
							(end 0.1016 0.1778)
						)
						(arc
							(start -0.1016 0.1778)
							(mid -0.137521 0.162921)
							(end -0.1524 0.127)
						)
						(arc
							(start -0.1524 -0.127)
							(mid -0.137521 -0.162921)
							(end -0.1016 -0.1778)
						)
						(arc
							(start 0.1016 -0.1778)
							(mid 0.137521 -0.162921)
							(end 0.1524 -0.127)
						)
					)
					(width 0)
					(fill yes)
				)
			)
		)
	)
	(footprint ""
		(layer "B.Cu")
		(at 93.311472 -67.625214 180)
		(property "Reference" "C201"
			(at 0 0 0)
			(layer "B.SilkS")
			(hide yes)
			(effects
				(font
					(size 1.27 1.27)
				)
				(justify mirror)
			)
		)
		(property "Value" "SC10U6D3V2MX-GP-U"
			(at 1.524 -1.905 180)
			(unlocked yes)
			(layer "B.Fab")
			(hide yes)
			(effects
				(font
					(size 1.016 1.016)
					(thickness 0.1524)
				)
				(justify mirror)
			)
		)
		(property "Device Type" "C402-TO0D2H28"
			(at 1.524 -3.429 180)
			(unlocked yes)
			(layer "B.Fab")
			(hide yes)
			(effects
				(font
					(size 1.016 1.016)
					(thickness 0.1524)
				)
				(justify mirror)
			)
		)
		(duplicate_pad_numbers_are_jumpers no)
		(fp_rect
			(start 0.4826 0.889)
			(end -0.4826 -0.889)
			(stroke
				(width 0)
				(type default)
			)
			(fill no)
			(layer "B.CrtYd")
		)
		(fp_rect
			(start 0.4826 0.889)
			(end -0.4826 -0.889)
			(stroke
				(width 0)
				(type default)
			)
			(fill no)
			(layer "B.Fab")
		)
		(pad "1" smd custom
			(at 0 -0.4572)
			(size 0.1524 0.1524)
			(layers "B.Cu" "B.Mask" "B.Paste")
			(net "PLLDDR_VDDA18")
			(options
				(clearance outline)
				(anchor circle)
			)
			(primitives
				(gr_poly
					(pts
						(arc
							(start -0.254 -0.3048)
							(mid -0.325842 -0.275042)
							(end -0.3556 -0.2032)
						)
						(arc
							(start -0.3556 0.2032)
							(mid -0.325842 0.275042)
							(end -0.254 0.3048)
						)
						(arc
							(start 0.254 0.3048)
							(mid 0.325842 0.275042)
							(end 0.3556 0.2032)
						)
						(arc
							(start 0.3556 -0.2032)
							(mid 0.325842 -0.275042)
							(end 0.254 -0.3048)
						)
					)
					(width 0)
					(fill yes)
				)
			)
		)
		(pad "2" smd custom
			(at 0 0.4572)
			(size 0.1524 0.1524)
			(layers "B.Cu" "B.Mask" "B.Paste")
			(net "GND")
			(options
				(clearance outline)
				(anchor circle)
			)
			(primitives
				(gr_poly
					(pts
						(arc
							(start -0.254 -0.3048)
							(mid -0.325842 -0.275042)
							(end -0.3556 -0.2032)
						)
						(arc
							(start -0.3556 0.2032)
							(mid -0.325842 0.275042)
							(end -0.254 0.3048)
						)
						(arc
							(start 0.254 0.3048)
							(mid 0.325842 0.275042)
							(end 0.3556 0.2032)
						)
						(arc
							(start 0.3556 -0.2032)
							(mid 0.325842 -0.275042)
							(end 0.254 -0.3048)
						)
					)
					(width 0)
					(fill yes)
				)
			)
		)
	)
	(footprint ""
		(layer "B.Cu")
		(at 121.4374 -39.4716 180)
		(property "Reference" "C56"
			(at 0 0 0)
			(layer "B.SilkS")
			(hide yes)
			(effects
				(font
					(size 1.27 1.27)
				)
				(justify mirror)
			)
		)
		(property "Value" "SCD01U16V1KX-GP"
			(at 2.8321 -1.7399 180)
			(unlocked yes)
			(layer "B.Fab")
			(hide yes)
			(effects
				(font
					(size 1.016 1.016)
					(thickness 0.1524)
				)
				(justify mirror)
			)
		)
		(property "Device Type" "C0201H13"
			(at 2.8321 -3.2639 180)
			(unlocked yes)
			(layer "B.Fab")
			(hide yes)
			(effects
				(font
					(size 1.016 1.016)
					(thickness 0.1524)
				)
				(justify mirror)
			)
		)
		(duplicate_pad_numbers_are_jumpers no)
		(fp_rect
			(start 0.2794 0.6477)
			(end -0.2794 -0.6477)
			(stroke
				(width 0)
				(type default)
			)
			(fill no)
			(layer "B.CrtYd")
		)
		(fp_rect
			(start 0.2794 0.6477)
			(end -0.2794 -0.6477)
			(stroke
				(width 0)
				(type default)
			)
			(fill no)
			(layer "B.Fab")
		)
		(pad "1" smd custom
			(at 0 -0.2794)
			(size 0.0762 0.0762)
			(layers "B.Cu" "B.Mask" "B.Paste")
			(net "PHY_DPB_TO_SCC_36_DN")
			(options
				(clearance outline)
				(anchor circle)
			)
			(primitives
				(gr_poly
					(pts
						(arc
							(start 0.1524 0.127)
							(mid 0.137521 0.162921)
							(end 0.1016 0.1778)
						)
						(arc
							(start -0.1016 0.1778)
							(mid -0.137521 0.162921)
							(end -0.1524 0.127)
						)
						(arc
							(start -0.1524 -0.127)
							(mid -0.137521 -0.162921)
							(end -0.1016 -0.1778)
						)
						(arc
							(start 0.1016 -0.1778)
							(mid 0.137521 -0.162921)
							(end 0.1524 -0.127)
						)
					)
					(width 0)
					(fill yes)
				)
			)
		)
		(pad "2" smd custom
			(at 0 0.2794)
			(size 0.0762 0.0762)
			(layers "B.Cu" "B.Mask" "B.Paste")
			(net "PHY_DPB_TO_SCC_C_36_DN")
			(options
				(clearance outline)
				(anchor circle)
			)
			(primitives
				(gr_poly
					(pts
						(arc
							(start 0.1524 0.127)
							(mid 0.137521 0.162921)
							(end 0.1016 0.1778)
						)
						(arc
							(start -0.1016 0.1778)
							(mid -0.137521 0.162921)
							(end -0.1524 0.127)
						)
						(arc
							(start -0.1524 -0.127)
							(mid -0.137521 -0.162921)
							(end -0.1016 -0.1778)
						)
						(arc
							(start 0.1016 -0.1778)
							(mid 0.137521 -0.162921)
							(end 0.1524 -0.127)
						)
					)
					(width 0)
					(fill yes)
				)
			)
		)
	)
	(footprint ""
		(layer "B.Cu")
		(at 179.767738 -35.155124 -90)
		(property "Reference" "R273"
			(at 0 0 90)
			(layer "B.SilkS")
			(hide yes)
			(effects
				(font
					(size 1.27 1.27)
				)
				(justify mirror)
			)
		)
		(property "Value" "10KR2F-2-GP"
			(at -0.064008 -3.993896 270)
			(unlocked yes)
			(layer "B.Fab")
			(hide yes)
			(effects
				(font
					(size 1.016 1.016)
					(thickness 0.1524)
				)
				(justify mirror)
			)
		)
		(property "Device Type" "R402H16"
			(at -0.064008 -5.517896 270)
			(unlocked yes)
			(layer "B.Fab")
			(hide yes)
			(effects
				(font
					(size 1.016 1.016)
					(thickness 0.1524)
				)
				(justify mirror)
			)
		)
		(duplicate_pad_numbers_are_jumpers no)
		(fp_line
			(start -0.508 -0.9398)
			(end 0.508 -0.9398)
			(stroke
				(width 0.1524)
				(type default)
			)
			(layer "B.SilkS")
		)
		(fp_line
			(start 0.508 -0.9398)
			(end 0.508 0.9398)
			(stroke
				(width 0.1524)
				(type default)
			)
			(layer "B.SilkS")
		)
		(fp_rect
			(start 0.508 0.9398)
			(end -0.508 -0.9398)
			(stroke
				(width 0)
				(type default)
			)
			(fill no)
			(layer "B.CrtYd")
		)
		(fp_rect
			(start 0.508 0.9398)
			(end -0.508 -0.9398)
			(stroke
				(width 0)
				(type default)
			)
			(fill no)
			(layer "B.Fab")
		)
		(pad "1" smd custom
			(at 0 -0.4445 90)
			(size 0.1397 0.1397)
			(layers "B.Cu" "B.Mask" "B.Paste")
			(net "SYS_DBMODE0")
			(options
				(clearance outline)
				(anchor circle)
			)
			(primitives
				(gr_poly
					(pts
						(arc
							(start -0.1778 0.2794)
							(mid -0.249642 0.249642)
							(end -0.2794 0.1778)
						)
						(arc
							(start -0.2794 -0.1778)
							(mid -0.249642 -0.249642)
							(end -0.1778 -0.2794)
						)
						(arc
							(start 0.1778 -0.2794)
							(mid 0.249642 -0.249642)
							(end 0.2794 -0.1778)
						)
						(arc
							(start 0.2794 0.1778)
							(mid 0.249642 0.249642)
							(end 0.1778 0.2794)
						)
					)
					(width 0)
					(fill yes)
				)
			)
		)
		(pad "2" smd custom
			(at 0 0.4445 90)
			(size 0.1397 0.1397)
			(layers "B.Cu" "B.Mask" "B.Paste")
			(net "GND")
			(options
				(clearance outline)
				(anchor circle)
			)
			(primitives
				(gr_poly
					(pts
						(arc
							(start -0.1778 0.2794)
							(mid -0.249642 0.249642)
							(end -0.2794 0.1778)
						)
						(arc
							(start -0.2794 -0.1778)
							(mid -0.249642 -0.249642)
							(end -0.1778 -0.2794)
						)
						(arc
							(start 0.1778 -0.2794)
							(mid 0.249642 -0.249642)
							(end 0.2794 -0.1778)
						)
						(arc
							(start 0.2794 0.1778)
							(mid 0.249642 0.249642)
							(end 0.1778 0.2794)
						)
					)
					(width 0)
					(fill yes)
				)
			)
		)
	)
	(footprint ""
		(layer "B.Cu")
		(at 127.880872 -82.37855)
		(property "Reference" "TP36"
			(at 0 0 0)
			(layer "B.SilkS")
			(hide yes)
			(effects
				(font
					(size 1.27 1.27)
				)
				(justify mirror)
			)
		)
		(property "Value" "TPAD28-2-GP"
			(at 0.0127 -1.6637 0)
			(unlocked yes)
			(layer "B.Fab")
			(hide yes)
			(effects
				(font
					(size 1.016 1.016)
					(thickness 0.1524)
				)
				(justify mirror)
			)
		)
		(property "Device Type" "TPAD28"
			(at 0.0127 -3.1877 0)
			(unlocked yes)
			(layer "B.Fab")
			(hide yes)
			(effects
				(font
					(size 1.016 1.016)
					(thickness 0.1524)
				)
				(justify mirror)
			)
		)
		(duplicate_pad_numbers_are_jumpers no)
		(fp_poly
			(pts
				(arc
					(start 0.3556 0)
					(mid -0.3556 0)
					(end 0.3556 0)
				)
			)
			(stroke
				(width 0)
				(type default)
			)
			(fill no)
			(layer "B.CrtYd")
		)
		(fp_poly
			(pts
				(arc
					(start 0.6096 0)
					(mid -0.6096 0)
					(end 0.6096 0)
				)
			)
			(stroke
				(width 0)
				(type default)
			)
			(fill no)
			(layer "B.Fab")
		)
		(pad "1" smd circle
			(at 0 0 180)
			(size 0.7112 0.7112)
			(layers "B.Cu" "B.Mask" "B.Paste")
			(net "UART_RTS")
		)
	)
	(footprint ""
		(layer "B.Cu")
		(at 189.7888 -32.3596 90)
		(property "Reference" "TP70"
			(at 0 0 90)
			(layer "B.SilkS")
			(hide yes)
			(effects
				(font
					(size 1.27 1.27)
				)
				(justify mirror)
			)
		)
		(property "Value" "TPAD28-2-GP"
			(at 0.0127 -1.6637 90)
			(unlocked yes)
			(layer "B.Fab")
			(hide yes)
			(effects
				(font
					(size 1.016 1.016)
					(thickness 0.1524)
				)
				(justify mirror)
			)
		)
		(property "Device Type" "TPAD28"
			(at 0.0127 -3.1877 90)
			(unlocked yes)
			(layer "B.Fab")
			(hide yes)
			(effects
				(font
					(size 1.016 1.016)
					(thickness 0.1524)
				)
				(justify mirror)
			)
		)
		(duplicate_pad_numbers_are_jumpers no)
		(fp_poly
			(pts
				(arc
					(start 0 0.3556)
					(mid 0 -0.3556)
					(end 0 0.3556)
				)
			)
			(stroke
				(width 0)
				(type default)
			)
			(fill no)
			(layer "B.CrtYd")
		)
		(fp_poly
			(pts
				(arc
					(start 0 0.6096)
					(mid 0 -0.6096)
					(end 0 0.6096)
				)
			)
			(stroke
				(width 0)
				(type default)
			)
			(fill no)
			(layer "B.Fab")
		)
		(pad "1" smd circle
			(at 0 0 270)
			(size 0.7112 0.7112)
			(layers "B.Cu" "B.Mask" "B.Paste")
			(net "IOC_GPIO_17")
		)
	)
	(footprint ""
		(layer "B.Cu")
		(at 158.496 -52.07)
		(property "Reference" "R194"
			(at 0 0 0)
			(layer "B.SilkS")
			(hide yes)
			(effects
				(font
					(size 1.27 1.27)
				)
				(justify mirror)
			)
		)
		(property "Value" "2K2R2F-GP"
			(at -0.064008 -3.993896 0)
			(unlocked yes)
			(layer "B.Fab")
			(hide yes)
			(effects
				(font
					(size 1.016 1.016)
					(thickness 0.1524)
				)
				(justify mirror)
			)
		)
		(property "Device Type" "R402H16"
			(at -0.064008 -5.517896 0)
			(unlocked yes)
			(layer "B.Fab")
			(hide yes)
			(effects
				(font
					(size 1.016 1.016)
					(thickness 0.1524)
				)
				(justify mirror)
			)
		)
		(duplicate_pad_numbers_are_jumpers no)
		(fp_line
			(start -0.508 -0.9398)
			(end 0.508 -0.9398)
			(stroke
				(width 0.1524)
				(type default)
			)
			(layer "B.SilkS")
		)
		(fp_line
			(start 0.508 -0.9398)
			(end 0.508 0.9398)
			(stroke
				(width 0.1524)
				(type default)
			)
			(layer "B.SilkS")
		)
		(fp_rect
			(start 0.508 0.9398)
			(end -0.508 -0.9398)
			(stroke
				(width 0)
				(type default)
			)
			(fill no)
			(layer "B.CrtYd")
		)
		(fp_rect
			(start 0.508 0.9398)
			(end -0.508 -0.9398)
			(stroke
				(width 0)
				(type default)
			)
			(fill no)
			(layer "B.Fab")
		)
		(pad "1" smd custom
			(at 0 -0.4445 180)
			(size 0.1397 0.1397)
			(layers "B.Cu" "B.Mask" "B.Paste")
			(net "P1V8_C")
			(options
				(clearance outline)
				(anchor circle)
			)
			(primitives
				(gr_poly
					(pts
						(arc
							(start -0.1778 0.2794)
							(mid -0.249642 0.249642)
							(end -0.2794 0.1778)
						)
						(arc
							(start -0.2794 -0.1778)
							(mid -0.249642 -0.249642)
							(end -0.1778 -0.2794)
						)
						(arc
							(start 0.1778 -0.2794)
							(mid 0.249642 -0.249642)
							(end 0.2794 -0.1778)
						)
						(arc
							(start 0.2794 0.1778)
							(mid 0.249642 0.249642)
							(end 0.1778 0.2794)
						)
					)
					(width 0)
					(fill yes)
				)
			)
		)
		(pad "2" smd custom
			(at 0 0.4445 180)
			(size 0.1397 0.1397)
			(layers "B.Cu" "B.Mask" "B.Paste")
			(net "SIO_DIN_0")
			(options
				(clearance outline)
				(anchor circle)
			)
			(primitives
				(gr_poly
					(pts
						(arc
							(start -0.1778 0.2794)
							(mid -0.249642 0.249642)
							(end -0.2794 0.1778)
						)
						(arc
							(start -0.2794 -0.1778)
							(mid -0.249642 -0.249642)
							(end -0.1778 -0.2794)
						)
						(arc
							(start 0.1778 -0.2794)
							(mid 0.249642 -0.249642)
							(end 0.2794 -0.1778)
						)
						(arc
							(start 0.2794 0.1778)
							(mid 0.249642 0.249642)
							(end 0.1778 0.2794)
						)
					)
					(width 0)
					(fill yes)
				)
			)
		)
	)
	(footprint ""
		(layer "B.Cu")
		(at 109.3978 -44.2214 180)
		(property "Reference" "C71"
			(at 0 0 0)
			(layer "B.SilkS")
			(hide yes)
			(effects
				(font
					(size 1.27 1.27)
				)
				(justify mirror)
			)
		)
		(property "Value" "SCD01U16V1KX-GP"
			(at 2.8321 -1.7399 180)
			(unlocked yes)
			(layer "B.Fab")
			(hide yes)
			(effects
				(font
					(size 1.016 1.016)
					(thickness 0.1524)
				)
				(justify mirror)
			)
		)
		(property "Device Type" "C0201H13"
			(at 2.8321 -3.2639 180)
			(unlocked yes)
			(layer "B.Fab")
			(hide yes)
			(effects
				(font
					(size 1.016 1.016)
					(thickness 0.1524)
				)
				(justify mirror)
			)
		)
		(duplicate_pad_numbers_are_jumpers no)
		(fp_rect
			(start 0.2794 0.6477)
			(end -0.2794 -0.6477)
			(stroke
				(width 0)
				(type default)
			)
			(fill no)
			(layer "B.CrtYd")
		)
		(fp_rect
			(start 0.2794 0.6477)
			(end -0.2794 -0.6477)
			(stroke
				(width 0)
				(type default)
			)
			(fill no)
			(layer "B.Fab")
		)
		(pad "1" smd custom
			(at 0 -0.2794)
			(size 0.0762 0.0762)
			(layers "B.Cu" "B.Mask" "B.Paste")
			(net "PHY_DPB_TO_SCC_24_DP")
			(options
				(clearance outline)
				(anchor circle)
			)
			(primitives
				(gr_poly
					(pts
						(arc
							(start 0.1524 0.127)
							(mid 0.137521 0.162921)
							(end 0.1016 0.1778)
						)
						(arc
							(start -0.1016 0.1778)
							(mid -0.137521 0.162921)
							(end -0.1524 0.127)
						)
						(arc
							(start -0.1524 -0.127)
							(mid -0.137521 -0.162921)
							(end -0.1016 -0.1778)
						)
						(arc
							(start 0.1016 -0.1778)
							(mid 0.137521 -0.162921)
							(end 0.1524 -0.127)
						)
					)
					(width 0)
					(fill yes)
				)
			)
		)
		(pad "2" smd custom
			(at 0 0.2794)
			(size 0.0762 0.0762)
			(layers "B.Cu" "B.Mask" "B.Paste")
			(net "PHY_DPB_TO_SCC_C_24_DP")
			(options
				(clearance outline)
				(anchor circle)
			)
			(primitives
				(gr_poly
					(pts
						(arc
							(start 0.1524 0.127)
							(mid 0.137521 0.162921)
							(end 0.1016 0.1778)
						)
						(arc
							(start -0.1016 0.1778)
							(mid -0.137521 0.162921)
							(end -0.1524 0.127)
						)
						(arc
							(start -0.1524 -0.127)
							(mid -0.137521 -0.162921)
							(end -0.1016 -0.1778)
						)
						(arc
							(start 0.1016 -0.1778)
							(mid 0.137521 -0.162921)
							(end 0.1524 -0.127)
						)
					)
					(width 0)
					(fill yes)
				)
			)
		)
	)
)
